(kicad_pcb
	(version 20260206)
	(generator "pcbnew")
	(generator_version "10.0")
	(general
		(thickness 1.6)
		(legacy_teardrops no)
	)
	(paper "A4")
	(layers
		(0 "F.Cu" signal "TOP")
		(4 "In1.Cu" signal "GND")
		(6 "In2.Cu" signal "VCC")
		(8 "In3.Cu" signal "VCC1")
		(10 "In4.Cu" signal "GND1")
		(12 "In5.Cu" signal "IN1")
		(14 "In6.Cu" signal "GND2")
		(16 "In7.Cu" signal "IN2")
		(18 "In8.Cu" signal "GND3")
		(20 "In9.Cu" signal "IN3")
		(22 "In10.Cu" signal "GND4")
		(24 "In11.Cu" signal "IN4")
		(26 "In12.Cu" signal "GND5")
		(28 "In13.Cu" signal "IN5")
		(30 "In14.Cu" signal "GND6")
		(32 "In15.Cu" signal "IN6")
		(34 "In16.Cu" signal "GND7")
		(2 "B.Cu" signal "BOTTOM")
		(9 "F.Adhes" user "F.Adhesive")
		(11 "B.Adhes" user "B.Adhesive")
		(13 "F.Paste" user "Package Geometry/Pastemask Top")
		(15 "B.Paste" user "Package Geometry/Pastemask Bottom")
		(5 "F.SilkS" user "Ref Des/Silkscreen Top")
		(7 "B.SilkS" user "Ref Des/Silkscreen Bottom")
		(1 "F.Mask" user "Board Geometry/Soldermask Top")
		(3 "B.Mask" user "Board Geometry/Soldermask Bottom")
		(17 "Dwgs.User" user "User.Drawings")
		(19 "Cmts.User" user "User.Comments")
		(21 "Eco1.User" user "User.Eco1")
		(23 "Eco2.User" user "User.Eco2")
		(25 "Edge.Cuts" user "Board Geometry/Outline")
		(27 "Margin" user)
		(31 "F.CrtYd" user "Package Geometry/Place Bound Top")
		(29 "B.CrtYd" user "Package Geometry/Place Bound Bottom")
		(35 "F.Fab" user "Ref Des/Assembly Top")
		(33 "B.Fab" user "Ref Des/Assembly Bottom")
	)
	(setup
		(pad_to_mask_clearance 0)
		(allow_soldermask_bridges_in_footprints no)
		(tenting
			(front yes)
			(back yes)
		)
		(covering
			(front no)
			(back no)
		)
		(plugging
			(front no)
			(back no)
		)
		(capping no)
		(filling no)
		(pcbplotparams
			(layerselection 0x00000000_00000000_55555555_5755f5ff)
			(plot_on_all_layers_selection 0x00000000_00000000_00000000_00000000)
			(disableapertmacros no)
			(usegerberextensions no)
			(usegerberattributes yes)
			(usegerberadvancedattributes yes)
			(creategerberjobfile yes)
			(dashed_line_dash_ratio 12)
			(dashed_line_gap_ratio 3)
			(svgprecision 4)
			(plotframeref no)
			(mode 1)
			(useauxorigin no)
			(pdf_front_fp_property_popups yes)
			(pdf_back_fp_property_popups yes)
			(pdf_metadata yes)
			(pdf_single_document no)
			(dxfpolygonmode yes)
			(dxfimperialunits yes)
			(dxfusepcbnewfont yes)
			(psnegative no)
			(psa4output no)
			(plot_black_and_white yes)
			(sketchpadsonfab no)
			(plotpadnumbers no)
			(hidednponfab no)
			(sketchdnponfab yes)
			(crossoutdnponfab yes)
			(subtractmaskfromsilk no)
			(outputformat 1)
			(mirror no)
			(drillshape 1)
			(scaleselection 1)
			(outputdirectory "")
		)
	)
	(zone
		(layer "In15.Cu")
		(hatch none 0.5)
		(connect_pads
			(clearance 0)
		)
		(min_thickness 0.25)
		(keepout
			(tracks not_allowed)
			(vias allowed)
			(pads allowed)
			(copperpour not_allowed)
			(footprints allowed)
		)
		(placement
			(enabled no)
			(sheetname "")
		)
		(fill
			(thermal_gap 0.5)
			(thermal_bridge_width 0.5)
			(island_removal_mode 0)
		)
		(polygon
			(pts
				(arc
					(start 122.847862 -72.700134)
					(mid 112.552734 -72.700134)
					(end 122.847862 -72.700134)
				)
			)
		)
	)
	(zone
		(layer "In15.Cu")
		(hatch none 0.5)
		(connect_pads
			(clearance 0)
		)
		(min_thickness 0.25)
		(keepout
			(tracks not_allowed)
			(vias allowed)
			(pads allowed)
			(copperpour not_allowed)
			(footprints allowed)
		)
		(placement
			(enabled no)
			(sheetname "")
		)
		(fill
			(thermal_gap 0.5)
			(thermal_bridge_width 0.5)
			(island_removal_mode 0)
		)
		(polygon
			(pts
				(arc
					(start 355.04755 -72.69988)
					(mid 344.752422 -72.69988)
					(end 355.04755 -72.69988)
				)
			)
		)
	)
	(zone
		(layer "In15.Cu")
		(hatch none 0.5)
		(connect_pads
			(clearance 0)
		)
		(min_thickness 0.25)
		(keepout
			(tracks not_allowed)
			(vias allowed)
			(pads allowed)
			(copperpour not_allowed)
			(footprints allowed)
		)
		(placement
			(enabled no)
			(sheetname "")
		)
		(fill
			(thermal_gap 0.5)
			(thermal_bridge_width 0.5)
			(island_removal_mode 0)
		)
		(polygon
			(pts
				(arc
					(start 23.947628 -84.699856)
					(mid 13.6525 -84.699856)
					(end 23.947628 -84.699856)
				)
			)
		)
	)
	(zone
		(layer "In15.Cu")
		(hatch none 0.5)
		(connect_pads
			(clearance 0)
		)
		(min_thickness 0.25)
		(keepout
			(tracks allowed)
			(vias allowed)
			(pads allowed)
			(copperpour allowed)
			(footprints allowed)
		)
		(placement
			(enabled no)
			(sheetname "")
		)
		(fill
			(thermal_gap 0.5)
			(thermal_bridge_width 0.5)
			(island_removal_mode 0)
		)
		(polygon
			(pts
				(xy 332.7654 -212.1154) (xy 350.4692 -212.1154) (xy 351.3836 -213.0298) (xy 351.3836 -215.1126)
				(xy 352.0694 -215.7984) (xy 352.0694 -226.3902) (xy 351.0788 -227.3808) (xy 335.5594 -227.3808)
				(xy 334.1878 -226.0092) (xy 334.1878 -216.154) (xy 332.5622 -214.5284) (xy 332.5622 -212.3186)
			)
		)
	)
	(zone
		(layer "In15.Cu")
		(hatch none 0.5)
		(connect_pads
			(clearance 0)
		)
		(min_thickness 0.25)
		(keepout
			(tracks not_allowed)
			(vias allowed)
			(pads allowed)
			(copperpour not_allowed)
			(footprints allowed)
		)
		(placement
			(enabled no)
			(sheetname "")
		)
		(fill
			(thermal_gap 0.5)
			(thermal_bridge_width 0.5)
			(island_removal_mode 0)
		)
		(polygon
			(pts
				(arc
					(start 277.047452 -378.70003)
					(mid 266.752324 -378.70003)
					(end 277.047452 -378.70003)
				)
			)
		)
	)
	(zone
		(layer "In15.Cu")
		(hatch none 0.5)
		(connect_pads
			(clearance 0)
		)
		(min_thickness 0.25)
		(keepout
			(tracks not_allowed)
			(vias allowed)
			(pads allowed)
			(copperpour not_allowed)
			(footprints allowed)
		)
		(placement
			(enabled no)
			(sheetname "")
		)
		(fill
			(thermal_gap 0.5)
			(thermal_bridge_width 0.5)
			(island_removal_mode 0)
		)
		(polygon
			(pts
				(arc
					(start 204.54747 -393.100052)
					(mid 194.252342 -393.100052)
					(end 204.54747 -393.100052)
				)
			)
		)
	)
	(zone
		(layer "In15.Cu")
		(hatch none 0.5)
		(connect_pads
			(clearance 0)
		)
		(min_thickness 0.25)
		(keepout
			(tracks not_allowed)
			(vias allowed)
			(pads allowed)
			(copperpour not_allowed)
			(footprints allowed)
		)
		(placement
			(enabled no)
			(sheetname "")
		)
		(fill
			(thermal_gap 0.5)
			(thermal_bridge_width 0.5)
			(island_removal_mode 0)
		)
		(polygon
			(pts
				(arc
					(start 34.29889 -320.900044)
					(mid 25.000458 -320.900044)
					(end 34.29889 -320.900044)
				)
			)
		)
	)
	(zone
		(layer "In15.Cu")
		(hatch none 0.5)
		(connect_pads
			(clearance 0)
		)
		(min_thickness 0.25)
		(keepout
			(tracks not_allowed)
			(vias allowed)
			(pads allowed)
			(copperpour not_allowed)
			(footprints allowed)
		)
		(placement
			(enabled no)
			(sheetname "")
		)
		(fill
			(thermal_gap 0.5)
			(thermal_bridge_width 0.5)
			(island_removal_mode 0)
		)
		(polygon
			(pts
				(arc
					(start 382.59893 -270.89989)
					(mid 373.300498 -270.89989)
					(end 382.59893 -270.89989)
				)
			)
		)
	)
	(zone
		(layer "In15.Cu")
		(hatch none 0.5)
		(connect_pads
			(clearance 0)
		)
		(min_thickness 0.25)
		(keepout
			(tracks not_allowed)
			(vias allowed)
			(pads allowed)
			(copperpour not_allowed)
			(footprints allowed)
		)
		(placement
			(enabled no)
			(sheetname "")
		)
		(fill
			(thermal_gap 0.5)
			(thermal_bridge_width 0.5)
			(island_removal_mode 0)
		)
		(polygon
			(pts
				(arc
					(start 34.29889 -270.89989)
					(mid 25.000458 -270.89989)
					(end 34.29889 -270.89989)
				)
			)
		)
	)
	(zone
		(layer "In15.Cu")
		(hatch none 0.5)
		(connect_pads
			(clearance 0)
		)
		(min_thickness 0.25)
		(keepout
			(tracks not_allowed)
			(vias allowed)
			(pads allowed)
			(copperpour not_allowed)
			(footprints allowed)
		)
		(placement
			(enabled no)
			(sheetname "")
		)
		(fill
			(thermal_gap 0.5)
			(thermal_bridge_width 0.5)
			(island_removal_mode 0)
		)
		(polygon
			(pts
				(arc
					(start 326.498966 -270.89989)
					(mid 317.200534 -270.89989)
					(end 326.498966 -270.89989)
				)
			)
		)
	)
	(zone
		(layer "In15.Cu")
		(hatch none 0.5)
		(connect_pads
			(clearance 0)
		)
		(min_thickness 0.25)
		(keepout
			(tracks not_allowed)
			(vias allowed)
			(pads allowed)
			(copperpour not_allowed)
			(footprints allowed)
		)
		(placement
			(enabled no)
			(sheetname "")
		)
		(fill
			(thermal_gap 0.5)
			(thermal_bridge_width 0.5)
			(island_removal_mode 0)
		)
		(polygon
			(pts
				(arc
					(start 94.299024 -320.900044)
					(mid 85.000592 -320.900044)
					(end 94.299024 -320.900044)
				)
			)
		)
	)
	(zone
		(layer "In15.Cu")
		(hatch none 0.5)
		(connect_pads
			(clearance 0)
		)
		(min_thickness 0.25)
		(keepout
			(tracks allowed)
			(vias allowed)
			(pads allowed)
			(copperpour allowed)
			(footprints allowed)
		)
		(placement
			(enabled no)
			(sheetname "")
		)
		(fill
			(thermal_gap 0.5)
			(thermal_bridge_width 0.5)
			(island_removal_mode 0)
		)
		(polygon
			(pts
				(xy 231.728264 -88.610694) (xy 231.728264 -86.46668) (xy 234.027726 -86.46668) (xy 234.027726 -88.610694)
			)
		)
	)
	(zone
		(layer "In15.Cu")
		(hatch none 0.5)
		(connect_pads
			(clearance 0)
		)
		(min_thickness 0.25)
		(keepout
			(tracks not_allowed)
			(vias allowed)
			(pads allowed)
			(copperpour not_allowed)
			(footprints allowed)
		)
		(placement
			(enabled no)
			(sheetname "")
		)
		(fill
			(thermal_gap 0.5)
			(thermal_bridge_width 0.5)
			(island_removal_mode 0)
		)
		(polygon
			(pts
				(arc
					(start 150.398988 -270.89989)
					(mid 141.100556 -270.89989)
					(end 150.398988 -270.89989)
				)
			)
		)
	)
	(zone
		(layer "In15.Cu")
		(hatch none 0.5)
		(connect_pads
			(clearance 0)
		)
		(min_thickness 0.25)
		(keepout
			(tracks not_allowed)
			(vias allowed)
			(pads allowed)
			(copperpour not_allowed)
			(footprints allowed)
		)
		(placement
			(enabled no)
			(sheetname "")
		)
		(fill
			(thermal_gap 0.5)
			(thermal_bridge_width 0.5)
			(island_removal_mode 0)
		)
		(polygon
			(pts
				(arc
					(start 150.398988 -320.900044)
					(mid 141.100556 -320.900044)
					(end 150.398988 -320.900044)
				)
			)
		)
	)
	(zone
		(layer "In15.Cu")
		(hatch none 0.5)
		(connect_pads
			(clearance 0)
		)
		(min_thickness 0.25)
		(keepout
			(tracks allowed)
			(vias allowed)
			(pads allowed)
			(copperpour allowed)
			(footprints allowed)
		)
		(placement
			(enabled no)
			(sheetname "")
		)
		(fill
			(thermal_gap 0.5)
			(thermal_bridge_width 0.5)
			(island_removal_mode 0)
		)
		(polygon
			(pts
				(xy 232.475278 -83.730846) (xy 232.475278 -82.042508) (xy 234.745784 -82.042508) (xy 234.745784 -83.730846)
			)
		)
	)
	(zone
		(layer "In15.Cu")
		(hatch none 0.5)
		(connect_pads
			(clearance 0)
		)
		(min_thickness 0.25)
		(keepout
			(tracks allowed)
			(vias allowed)
			(pads allowed)
			(copperpour allowed)
			(footprints allowed)
		)
		(placement
			(enabled no)
			(sheetname "")
		)
		(fill
			(thermal_gap 0.5)
			(thermal_bridge_width 0.5)
			(island_removal_mode 0)
		)
		(polygon
			(pts
				(xy 73.66 -320.1162) (xy 79.7052 -320.1162) (xy 80.1116 -320.5226) (xy 80.1116 -322.7832) (xy 79.5274 -323.3674)
				(xy 75.8698 -323.3674) (xy 73.66 -321.1576)
			)
		)
	)
	(zone
		(layer "In15.Cu")
		(hatch none 0.5)
		(connect_pads
			(clearance 0)
		)
		(min_thickness 0.25)
		(keepout
			(tracks allowed)
			(vias allowed)
			(pads allowed)
			(copperpour allowed)
			(footprints allowed)
		)
		(placement
			(enabled no)
			(sheetname "")
		)
		(fill
			(thermal_gap 0.5)
			(thermal_bridge_width 0.5)
			(island_removal_mode 0)
		)
		(polygon
			(pts
				(xy 305.1556 -320.1416) (xy 311.3532 -320.1416) (xy 311.9628 -320.7512) (xy 311.9628 -323.2912)
				(xy 311.6326 -323.6214) (xy 307.2638 -323.6214) (xy 305.1556 -321.5132)
			)
		)
	)
	(zone
		(layer "In15.Cu")
		(hatch none 0.5)
		(connect_pads
			(clearance 0)
		)
		(min_thickness 0.25)
		(keepout
			(tracks allowed)
			(vias allowed)
			(pads allowed)
			(copperpour allowed)
			(footprints allowed)
		)
		(placement
			(enabled no)
			(sheetname "")
		)
		(fill
			(thermal_gap 0.5)
			(thermal_bridge_width 0.5)
			(island_removal_mode 0)
		)
		(polygon
			(pts
				(xy 43.716194 -371.879876) (xy 45.193204 -371.879876) (xy 45.364146 -371.708934) (xy 45.364146 -370.121942)
				(xy 45.10786 -369.865656) (xy 43.69181 -369.865656) (xy 43.69181 -371.855492)
			)
		)
	)
	(zone
		(layer "In15.Cu")
		(hatch none 0.5)
		(connect_pads
			(clearance 0)
		)
		(min_thickness 0.25)
		(keepout
			(tracks not_allowed)
			(vias allowed)
			(pads allowed)
			(copperpour not_allowed)
			(footprints allowed)
		)
		(placement
			(enabled no)
			(sheetname "")
		)
		(fill
			(thermal_gap 0.5)
			(thermal_bridge_width 0.5)
			(island_removal_mode 0)
		)
		(polygon
			(pts
				(arc
					(start 210.398868 -270.89989)
					(mid 201.100436 -270.89989)
					(end 210.398868 -270.89989)
				)
			)
		)
	)
	(zone
		(layer "In15.Cu")
		(hatch none 0.5)
		(connect_pads
			(clearance 0)
		)
		(min_thickness 0.25)
		(keepout
			(tracks not_allowed)
			(vias allowed)
			(pads allowed)
			(copperpour not_allowed)
			(footprints allowed)
		)
		(placement
			(enabled no)
			(sheetname "")
		)
		(fill
			(thermal_gap 0.5)
			(thermal_bridge_width 0.5)
			(island_removal_mode 0)
		)
		(polygon
			(pts
				(arc
					(start 453.94753 -84.699856)
					(mid 443.652402 -84.699856)
					(end 453.94753 -84.699856)
				)
			)
		)
	)
	(zone
		(layer "In15.Cu")
		(hatch none 0.5)
		(connect_pads
			(clearance 0)
		)
		(min_thickness 0.25)
		(keepout
			(tracks not_allowed)
			(vias allowed)
			(pads allowed)
			(copperpour not_allowed)
			(footprints allowed)
		)
		(placement
			(enabled no)
			(sheetname "")
		)
		(fill
			(thermal_gap 0.5)
			(thermal_bridge_width 0.5)
			(island_removal_mode 0)
		)
		(polygon
			(pts
				(arc
					(start 31.11246 -17.999964)
					(mid 20.817332 -17.999964)
					(end 31.11246 -17.999964)
				)
			)
		)
	)
	(zone
		(layer "In15.Cu")
		(hatch none 0.5)
		(connect_pads
			(clearance 0)
		)
		(min_thickness 0.25)
		(keepout
			(tracks not_allowed)
			(vias allowed)
			(pads allowed)
			(copperpour not_allowed)
			(footprints allowed)
		)
		(placement
			(enabled no)
			(sheetname "")
		)
		(fill
			(thermal_gap 0.5)
			(thermal_bridge_width 0.5)
			(island_removal_mode 0)
		)
		(polygon
			(pts
				(arc
					(start 94.299024 -270.89989)
					(mid 85.000592 -270.89989)
					(end 94.299024 -270.89989)
				)
			)
		)
	)
	(zone
		(layer "In15.Cu")
		(hatch none 0.5)
		(connect_pads
			(clearance 0)
		)
		(min_thickness 0.25)
		(keepout
			(tracks allowed)
			(vias allowed)
			(pads allowed)
			(copperpour allowed)
			(footprints allowed)
		)
		(placement
			(enabled no)
			(sheetname "")
		)
		(fill
			(thermal_gap 0.5)
			(thermal_bridge_width 0.5)
			(island_removal_mode 0)
		)
		(polygon
			(pts
				(xy 238.49076 -85.622638) (xy 238.49076 -83.953858) (xy 239.868456 -83.953858) (xy 239.868456 -85.622638)
			)
		)
	)
	(zone
		(layer "In15.Cu")
		(hatch none 0.5)
		(connect_pads
			(clearance 0)
		)
		(min_thickness 0.25)
		(keepout
			(tracks not_allowed)
			(vias allowed)
			(pads allowed)
			(copperpour not_allowed)
			(footprints allowed)
		)
		(placement
			(enabled no)
			(sheetname "")
		)
		(fill
			(thermal_gap 0.5)
			(thermal_bridge_width 0.5)
			(island_removal_mode 0)
		)
		(polygon
			(pts
				(arc
					(start 122.847608 -194.360038)
					(mid 112.55248 -194.360038)
					(end 122.847608 -194.360038)
				)
			)
		)
	)
	(zone
		(layer "In15.Cu")
		(hatch none 0.5)
		(connect_pads
			(clearance 0)
		)
		(min_thickness 0.25)
		(keepout
			(tracks not_allowed)
			(vias allowed)
			(pads allowed)
			(copperpour not_allowed)
			(footprints allowed)
		)
		(placement
			(enabled no)
			(sheetname "")
		)
		(fill
			(thermal_gap 0.5)
			(thermal_bridge_width 0.5)
			(island_removal_mode 0)
		)
		(polygon
			(pts
				(arc
					(start 264.447528 -98.700082)
					(mid 254.1524 -98.700082)
					(end 264.447528 -98.700082)
				)
			)
		)
	)
	(zone
		(layer "In15.Cu")
		(hatch none 0.5)
		(connect_pads
			(clearance 0)
		)
		(min_thickness 0.25)
		(keepout
			(tracks not_allowed)
			(vias allowed)
			(pads allowed)
			(copperpour not_allowed)
			(footprints allowed)
		)
		(placement
			(enabled no)
			(sheetname "")
		)
		(fill
			(thermal_gap 0.5)
			(thermal_bridge_width 0.5)
			(island_removal_mode 0)
		)
		(polygon
			(pts
				(arc
					(start 200.847452 -378.70003)
					(mid 190.552324 -378.70003)
					(end 200.847452 -378.70003)
				)
			)
		)
	)
	(zone
		(layer "In15.Cu")
		(hatch none 0.5)
		(connect_pads
			(clearance 0)
		)
		(min_thickness 0.25)
		(keepout
			(tracks allowed)
			(vias allowed)
			(pads allowed)
			(copperpour allowed)
			(footprints allowed)
		)
		(placement
			(enabled no)
			(sheetname "")
		)
		(fill
			(thermal_gap 0.5)
			(thermal_bridge_width 0.5)
			(island_removal_mode 0)
		)
		(polygon
			(pts
				(xy 44.985686 -372.539006) (xy 45.791374 -372.539006) (xy 46.108874 -372.221506) (xy 46.108874 -369.535964)
				(xy 45.351954 -369.535964) (xy 44.35094 -370.536978) (xy 44.35094 -371.90426)
			)
		)
	)
	(zone
		(layer "In15.Cu")
		(hatch none 0.5)
		(connect_pads
			(clearance 0)
		)
		(min_thickness 0.25)
		(keepout
			(tracks not_allowed)
			(vias allowed)
			(pads allowed)
			(copperpour not_allowed)
			(footprints allowed)
		)
		(placement
			(enabled no)
			(sheetname "")
		)
		(fill
			(thermal_gap 0.5)
			(thermal_bridge_width 0.5)
			(island_removal_mode 0)
		)
		(polygon
			(pts
				(arc
					(start 109.157516 -407.599896)
					(mid 98.862388 -407.599896)
					(end 109.157516 -407.599896)
				)
			)
		)
	)
	(zone
		(layer "In15.Cu")
		(hatch none 0.5)
		(connect_pads
			(clearance 0)
		)
		(min_thickness 0.25)
		(keepout
			(tracks allowed)
			(vias allowed)
			(pads allowed)
			(copperpour allowed)
			(footprints allowed)
		)
		(placement
			(enabled no)
			(sheetname "")
		)
		(fill
			(thermal_gap 0.5)
			(thermal_bridge_width 0.5)
			(island_removal_mode 0)
		)
		(polygon
			(pts
				(xy 234.18292 -88.10625) (xy 234.18292 -85.962236) (xy 236.482382 -85.962236) (xy 236.482382 -88.10625)
			)
		)
	)
	(zone
		(layer "In15.Cu")
		(hatch none 0.5)
		(connect_pads
			(clearance 0)
		)
		(min_thickness 0.25)
		(keepout
			(tracks not_allowed)
			(vias allowed)
			(pads allowed)
			(copperpour not_allowed)
			(footprints allowed)
		)
		(placement
			(enabled no)
			(sheetname "")
		)
		(fill
			(thermal_gap 0.5)
			(thermal_bridge_width 0.5)
			(island_removal_mode 0)
		)
		(polygon
			(pts
				(arc
					(start 347.362526 -17.999964)
					(mid 337.067398 -17.999964)
					(end 347.362526 -17.999964)
				)
			)
		)
	)
	(zone
		(layer "In15.Cu")
		(hatch none 0.5)
		(connect_pads
			(clearance 0)
		)
		(min_thickness 0.25)
		(keepout
			(tracks allowed)
			(vias allowed)
			(pads allowed)
			(copperpour allowed)
			(footprints allowed)
		)
		(placement
			(enabled no)
			(sheetname "")
		)
		(fill
			(thermal_gap 0.5)
			(thermal_bridge_width 0.5)
			(island_removal_mode 0)
		)
		(polygon
			(pts
				(xy 266.793726 -352.50628) (xy 413.402272 -352.50628) (xy 413.729424 -352.179128) (xy 413.729424 -341.06104)
				(xy 266.46632 -341.06104) (xy 265.303762 -342.223598) (xy 265.303762 -351.016316)
			)
		)
	)
	(zone
		(layer "In15.Cu")
		(hatch none 0.5)
		(connect_pads
			(clearance 0)
		)
		(min_thickness 0.25)
		(keepout
			(tracks allowed)
			(vias allowed)
			(pads allowed)
			(copperpour allowed)
			(footprints allowed)
		)
		(placement
			(enabled no)
			(sheetname "")
		)
		(fill
			(thermal_gap 0.5)
			(thermal_bridge_width 0.5)
			(island_removal_mode 0)
		)
		(polygon
			(pts
				(xy 414.6042 -320.2686) (xy 420.2938 -320.2686) (xy 420.7764 -320.7512) (xy 420.7764 -322.8848)
				(xy 420.2684 -323.3928) (xy 416.7886 -323.3928) (xy 414.5788 -321.183) (xy 414.5788 -320.294)
			)
		)
	)
	(zone
		(layer "In15.Cu")
		(hatch none 0.5)
		(connect_pads
			(clearance 0)
		)
		(min_thickness 0.25)
		(keepout
			(tracks not_allowed)
			(vias allowed)
			(pads allowed)
			(copperpour not_allowed)
			(footprints allowed)
		)
		(placement
			(enabled no)
			(sheetname "")
		)
		(fill
			(thermal_gap 0.5)
			(thermal_bridge_width 0.5)
			(island_removal_mode 0)
		)
		(polygon
			(pts
				(arc
					(start 266.499086 -270.89989)
					(mid 257.200654 -270.89989)
					(end 266.499086 -270.89989)
				)
			)
		)
	)
	(zone
		(layer "In15.Cu")
		(hatch none 0.5)
		(connect_pads
			(clearance 0)
		)
		(min_thickness 0.25)
		(keepout
			(tracks allowed)
			(vias allowed)
			(pads allowed)
			(copperpour allowed)
			(footprints allowed)
		)
		(placement
			(enabled no)
			(sheetname "")
		)
		(fill
			(thermal_gap 0.5)
			(thermal_bridge_width 0.5)
			(island_removal_mode 0)
		)
		(polygon
			(pts
				(xy 83.9724 -310.1848) (xy 83.9724 -305.2318) (xy 84.6328 -304.5714) (xy 86.868 -304.5714) (xy 87.0966 -304.8)
				(xy 87.0966 -310.007) (xy 86.9188 -310.1848)
			)
		)
	)
	(zone
		(layer "In15.Cu")
		(hatch none 0.5)
		(connect_pads
			(clearance 0)
		)
		(min_thickness 0.25)
		(keepout
			(tracks not_allowed)
			(vias allowed)
			(pads allowed)
			(copperpour not_allowed)
			(footprints allowed)
		)
		(placement
			(enabled no)
			(sheetname "")
		)
		(fill
			(thermal_gap 0.5)
			(thermal_bridge_width 0.5)
			(island_removal_mode 0)
		)
		(polygon
			(pts
				(arc
					(start 273.347434 -393.099798)
					(mid 263.052306 -393.099798)
					(end 273.347434 -393.099798)
				)
			)
		)
	)
	(zone
		(layer "In15.Cu")
		(hatch none 0.5)
		(connect_pads
			(clearance 0)
		)
		(min_thickness 0.25)
		(keepout
			(tracks not_allowed)
			(vias allowed)
			(pads allowed)
			(copperpour not_allowed)
			(footprints allowed)
		)
		(placement
			(enabled no)
			(sheetname "")
		)
		(fill
			(thermal_gap 0.5)
			(thermal_bridge_width 0.5)
			(island_removal_mode 0)
		)
		(polygon
			(pts
				(arc
					(start 20.947634 -194.360038)
					(mid 10.652506 -194.360038)
					(end 20.947634 -194.360038)
				)
			)
		)
	)
	(zone
		(layer "In15.Cu")
		(hatch none 0.5)
		(connect_pads
			(clearance 0)
		)
		(min_thickness 0.25)
		(keepout
			(tracks not_allowed)
			(vias allowed)
			(pads allowed)
			(copperpour not_allowed)
			(footprints allowed)
		)
		(placement
			(enabled no)
			(sheetname "")
		)
		(fill
			(thermal_gap 0.5)
			(thermal_bridge_width 0.5)
			(island_removal_mode 0)
		)
		(polygon
			(pts
				(arc
					(start 213.44763 -98.700082)
					(mid 203.152502 -98.700082)
					(end 213.44763 -98.700082)
				)
			)
		)
	)
	(zone
		(layer "In15.Cu")
		(hatch none 0.5)
		(connect_pads
			(clearance 0)
		)
		(min_thickness 0.25)
		(keepout
			(tracks not_allowed)
			(vias allowed)
			(pads allowed)
			(copperpour not_allowed)
			(footprints allowed)
		)
		(placement
			(enabled no)
			(sheetname "")
		)
		(fill
			(thermal_gap 0.5)
			(thermal_bridge_width 0.5)
			(island_removal_mode 0)
		)
		(polygon
			(pts
				(arc
					(start 238.947706 -194.359784)
					(mid 228.652578 -194.359784)
					(end 238.947706 -194.359784)
				)
			)
		)
	)
	(zone
		(layer "In15.Cu")
		(hatch none 0.5)
		(connect_pads
			(clearance 0)
		)
		(min_thickness 0.25)
		(keepout
			(tracks not_allowed)
			(vias allowed)
			(pads allowed)
			(copperpour not_allowed)
			(footprints allowed)
		)
		(placement
			(enabled no)
			(sheetname "")
		)
		(fill
			(thermal_gap 0.5)
			(thermal_bridge_width 0.5)
			(island_removal_mode 0)
		)
		(polygon
			(pts
				(xy 419.529514 -296.489374) (xy 419.529514 -296.089832) (xy 419.758622 -295.860724) (xy 432.284378 -295.860724)
				(xy 434.469032 -293.67607) (xy 437.131714 -293.67607) (xy 440.70524 -290.102544) (xy 445.157352 -290.102544)
				(xy 448.546982 -286.712914) (xy 455.896472 -286.712914) (xy 456.388978 -287.20542) (xy 462.646522 -287.20542)
				(xy 463.610452 -288.16935) (xy 463.610452 -307.65369) (xy 463.262218 -308.001924) (xy 462.76133 -308.001924)
				(xy 462.543144 -307.783738) (xy 462.543144 -307.41874) (xy 462.73212 -307.229764) (xy 463.3341 -307.229764)
				(xy 463.435192 -307.128672) (xy 463.435192 -288.26587) (xy 462.587848 -287.418526) (xy 456.085448 -287.418526)
				(xy 455.619612 -286.95269) (xy 448.661282 -286.95269) (xy 445.250316 -290.363656) (xy 440.78525 -290.363656)
				(xy 437.273192 -293.875714) (xy 434.567584 -293.875714) (xy 432.381406 -296.061892) (xy 420.292276 -296.061892)
				(xy 420.084504 -296.269664) (xy 420.084504 -296.51452) (xy 419.983412 -296.615612) (xy 419.655752 -296.615612)
			)
		)
	)
	(zone
		(layer "In15.Cu")
		(hatch none 0.5)
		(connect_pads
			(clearance 0)
		)
		(min_thickness 0.25)
		(keepout
			(tracks not_allowed)
			(vias allowed)
			(pads allowed)
			(copperpour not_allowed)
			(footprints allowed)
		)
		(placement
			(enabled no)
			(sheetname "")
		)
		(fill
			(thermal_gap 0.5)
			(thermal_bridge_width 0.5)
			(island_removal_mode 0)
		)
		(polygon
			(pts
				(xy 232.283 -307.895498) (xy 232.511854 -307.895498) (xy 232.960418 -307.446934) (xy 232.960418 -290.406328)
				(xy 229.493318 -286.939228) (xy 224.517966 -286.939228) (xy 224.097088 -286.51835) (xy 214.452454 -286.51835)
				(xy 210.639406 -290.331398) (xy 209.750152 -290.331398) (xy 206.511906 -293.569644) (xy 205.313534 -293.569644)
				(xy 204.83957 -294.043608) (xy 201.484484 -294.043608) (xy 199.668384 -295.859708) (xy 187.544964 -295.859708)
				(xy 187.302648 -296.102024) (xy 187.302648 -296.416222) (xy 187.483496 -296.59707) (xy 187.715398 -296.59707)
				(xy 187.851034 -296.461434) (xy 187.851034 -296.131234) (xy 187.98413 -295.998138) (xy 199.801734 -295.998138)
				(xy 201.532744 -294.267128) (xy 204.842872 -294.267128) (xy 205.369922 -293.740078) (xy 206.59471 -293.740078)
				(xy 209.8167 -290.518088) (xy 210.889596 -290.518088) (xy 214.668354 -286.73933) (xy 223.561402 -286.73933)
				(xy 224.128838 -287.306766) (xy 229.529386 -287.306766) (xy 232.78846 -290.56584) (xy 232.78846 -306.899818)
				(xy 232.565194 -307.123084) (xy 232.272078 -307.123084) (xy 232.053638 -307.341524) (xy 232.053638 -307.666136)
			)
		)
	)
	(zone
		(layer "In15.Cu")
		(hatch none 0.5)
		(connect_pads
			(clearance 0)
		)
		(min_thickness 0.25)
		(keepout
			(tracks allowed)
			(vias allowed)
			(pads allowed)
			(copperpour allowed)
			(footprints allowed)
		)
		(placement
			(enabled no)
			(sheetname "")
		)
		(fill
			(thermal_gap 0.5)
			(thermal_bridge_width 0.5)
			(island_removal_mode 0)
		)
		(polygon
			(pts
				(xy 316.2046 -309.5244) (xy 316.2046 -305.3842) (xy 316.865 -304.7238) (xy 318.5922 -304.7238) (xy 318.8716 -305.0032)
				(xy 318.8716 -308.9148) (xy 318.262 -309.5244)
			)
		)
	)
	(zone
		(layer "In15.Cu")
		(hatch none 0.5)
		(connect_pads
			(clearance 0)
		)
		(min_thickness 0.25)
		(keepout
			(tracks not_allowed)
			(vias allowed)
			(pads allowed)
			(copperpour not_allowed)
			(footprints allowed)
		)
		(placement
			(enabled no)
			(sheetname "")
		)
		(fill
			(thermal_gap 0.5)
			(thermal_bridge_width 0.5)
			(island_removal_mode 0)
		)
		(polygon
			(pts
				(arc
					(start 382.59893 -320.900044)
					(mid 373.300498 -320.900044)
					(end 382.59893 -320.900044)
				)
			)
		)
	)
	(zone
		(layer "In15.Cu")
		(hatch none 0.5)
		(connect_pads
			(clearance 0)
		)
		(min_thickness 0.25)
		(keepout
			(tracks allowed)
			(vias allowed)
			(pads allowed)
			(copperpour allowed)
			(footprints allowed)
		)
		(placement
			(enabled no)
			(sheetname "")
		)
		(fill
			(thermal_gap 0.5)
			(thermal_bridge_width 0.5)
			(island_removal_mode 0)
		)
		(polygon
			(pts
				(xy 231.0384 -215.392) (xy 231.3686 -215.392) (xy 231.6734 -215.6968) (xy 231.6734 -216.789) (xy 232.0036 -217.1192)
				(xy 234.7468 -217.1192) (xy 234.8484 -217.0176) (xy 235.2294 -217.0176) (xy 235.3056 -217.0938)
				(xy 235.3056 -217.424) (xy 235.0008 -217.7288) (xy 231.267 -217.7288) (xy 231.0384 -217.5002)
			)
		)
	)
	(zone
		(layer "In15.Cu")
		(hatch none 0.5)
		(connect_pads
			(clearance 0)
		)
		(min_thickness 0.25)
		(keepout
			(tracks not_allowed)
			(vias allowed)
			(pads allowed)
			(copperpour not_allowed)
			(footprints allowed)
		)
		(placement
			(enabled no)
			(sheetname "")
		)
		(fill
			(thermal_gap 0.5)
			(thermal_bridge_width 0.5)
			(island_removal_mode 0)
		)
		(polygon
			(pts
				(arc
					(start 266.499086 -320.900044)
					(mid 257.200654 -320.900044)
					(end 266.499086 -320.900044)
				)
			)
		)
	)
	(zone
		(layer "In15.Cu")
		(hatch none 0.5)
		(connect_pads
			(clearance 0)
		)
		(min_thickness 0.25)
		(keepout
			(tracks allowed)
			(vias allowed)
			(pads allowed)
			(copperpour allowed)
			(footprints allowed)
		)
		(placement
			(enabled no)
			(sheetname "")
		)
		(fill
			(thermal_gap 0.5)
			(thermal_bridge_width 0.5)
			(island_removal_mode 0)
		)
		(polygon
			(pts
				(xy 391.033 -320.1924) (xy 397.7386 -320.1924) (xy 398.0942 -320.548) (xy 398.0942 -321.8434) (xy 397.6624 -322.2752)
				(xy 391.795 -322.2752) (xy 390.7536 -321.2338) (xy 390.7536 -320.4718)
			)
		)
	)
	(zone
		(layer "In15.Cu")
		(hatch none 0.5)
		(connect_pads
			(clearance 0)
		)
		(min_thickness 0.25)
		(keepout
			(tracks not_allowed)
			(vias allowed)
			(pads allowed)
			(copperpour not_allowed)
			(footprints allowed)
		)
		(placement
			(enabled no)
			(sheetname "")
		)
		(fill
			(thermal_gap 0.5)
			(thermal_bridge_width 0.5)
			(island_removal_mode 0)
		)
		(polygon
			(pts
				(arc
					(start 326.498966 -320.900044)
					(mid 317.200534 -320.900044)
					(end 326.498966 -320.900044)
				)
			)
		)
	)
	(zone
		(layer "In15.Cu")
		(hatch none 0.5)
		(connect_pads
			(clearance 0)
		)
		(min_thickness 0.25)
		(keepout
			(tracks not_allowed)
			(vias allowed)
			(pads allowed)
			(copperpour not_allowed)
			(footprints allowed)
		)
		(placement
			(enabled no)
			(sheetname "")
		)
		(fill
			(thermal_gap 0.5)
			(thermal_bridge_width 0.5)
			(island_removal_mode 0)
		)
		(polygon
			(pts
				(arc
					(start 115.162584 -17.999964)
					(mid 104.867456 -17.999964)
					(end 115.162584 -17.999964)
				)
			)
		)
	)
	(zone
		(layer "In15.Cu")
		(hatch none 0.5)
		(connect_pads
			(clearance 0)
		)
		(min_thickness 0.25)
		(keepout
			(tracks not_allowed)
			(vias allowed)
			(pads allowed)
			(copperpour not_allowed)
			(footprints allowed)
		)
		(placement
			(enabled no)
			(sheetname "")
		)
		(fill
			(thermal_gap 0.5)
			(thermal_bridge_width 0.5)
			(island_removal_mode 0)
		)
		(polygon
			(pts
				(arc
					(start 355.04755 -194.360038)
					(mid 344.752422 -194.360038)
					(end 355.04755 -194.360038)
				)
			)
		)
	)
	(zone
		(layer "In16.Cu")
		(hatch none 0.5)
		(connect_pads
			(clearance 0)
		)
		(min_thickness 0.25)
		(keepout
			(tracks not_allowed)
			(vias allowed)
			(pads allowed)
			(copperpour not_allowed)
			(footprints allowed)
		)
		(placement
			(enabled no)
			(sheetname "")
		)
		(fill
			(thermal_gap 0.5)
			(thermal_bridge_width 0.5)
			(island_removal_mode 0)
		)
		(polygon
			(pts
				(arc
					(start 441.439808 21.117052)
					(mid 441.462126 21.170934)
					(end 441.516008 21.193252)
				)
				(arc
					(start 442.128148 21.193252)
					(mid 442.18203 21.170934)
					(end 442.204348 21.117052)
				)
				(arc
					(start 442.204348 20.019772)
					(mid 442.18203 19.96589)
					(end 442.128148 19.943572)
				)
				(arc
					(start 441.516008 19.943572)
					(mid 441.462126 19.96589)
					(end 441.439808 20.019772)
				)
			)
		)
	)
	(zone
		(layer "In16.Cu")
		(hatch none 0.5)
		(connect_pads
			(clearance 0)
		)
		(min_thickness 0.25)
		(keepout
			(tracks not_allowed)
			(vias allowed)
			(pads allowed)
			(copperpour not_allowed)
			(footprints allowed)
		)
		(placement
			(enabled no)
			(sheetname "")
		)
		(fill
			(thermal_gap 0.5)
			(thermal_bridge_width 0.5)
			(island_removal_mode 0)
		)
		(polygon
			(pts
				(arc
					(start 274.22856 20.026884)
					(mid 274.206242 19.973002)
					(end 274.15236 19.950684)
				)
				(arc
					(start 273.54022 19.950684)
					(mid 273.486338 19.973002)
					(end 273.46402 20.026884)
				)
				(arc
					(start 273.46402 21.124164)
					(mid 273.486338 21.178046)
					(end 273.54022 21.200364)
				)
				(arc
					(start 274.15236 21.200364)
					(mid 274.206242 21.178046)
					(end 274.22856 21.124164)
				)
			)
		)
	)
	(zone
		(layer "In16.Cu")
		(hatch none 0.5)
		(connect_pads
			(clearance 0)
		)
		(min_thickness 0.25)
		(keepout
			(tracks not_allowed)
			(vias allowed)
			(pads allowed)
			(copperpour not_allowed)
			(footprints allowed)
		)
		(placement
			(enabled no)
			(sheetname "")
		)
		(fill
			(thermal_gap 0.5)
			(thermal_bridge_width 0.5)
			(island_removal_mode 0)
		)
		(polygon
			(pts
				(arc
					(start 458.040232 11.264392)
					(mid 458.06255 11.318274)
					(end 458.116432 11.340592)
				)
				(arc
					(start 458.728572 11.340592)
					(mid 458.782454 11.318274)
					(end 458.804772 11.264392)
				)
				(arc
					(start 458.804772 10.167112)
					(mid 458.782454 10.11323)
					(end 458.728572 10.090912)
				)
				(arc
					(start 458.116432 10.090912)
					(mid 458.06255 10.11323)
					(end 458.040232 10.167112)
				)
			)
		)
	)
	(zone
		(layer "In16.Cu")
		(hatch none 0.5)
		(connect_pads
			(clearance 0)
		)
		(min_thickness 0.25)
		(keepout
			(tracks not_allowed)
			(vias allowed)
			(pads allowed)
			(copperpour not_allowed)
			(footprints allowed)
		)
		(placement
			(enabled no)
			(sheetname "")
		)
		(fill
			(thermal_gap 0.5)
			(thermal_bridge_width 0.5)
			(island_removal_mode 0)
		)
		(polygon
			(pts
				(arc
					(start 311.645808 21.117052)
					(mid 311.668126 21.170934)
					(end 311.722008 21.193252)
				)
				(arc
					(start 312.334148 21.193252)
					(mid 312.38803 21.170934)
					(end 312.410348 21.117052)
				)
				(arc
					(start 312.410348 20.019772)
					(mid 312.38803 19.96589)
					(end 312.334148 19.943572)
				)
				(arc
					(start 311.722008 19.943572)
					(mid 311.668126 19.96589)
					(end 311.645808 20.019772)
				)
			)
		)
	)
	(zone
		(layer "In16.Cu")
		(hatch none 0.5)
		(connect_pads
			(clearance 0)
		)
		(min_thickness 0.25)
		(keepout
			(tracks not_allowed)
			(vias allowed)
			(pads allowed)
			(copperpour not_allowed)
			(footprints allowed)
		)
		(placement
			(enabled no)
			(sheetname "")
		)
		(fill
			(thermal_gap 0.5)
			(thermal_bridge_width 0.5)
			(island_removal_mode 0)
		)
		(polygon
			(pts
				(arc
					(start 329.21956 10.108184)
					(mid 329.197242 10.054302)
					(end 329.14336 10.031984)
				)
				(arc
					(start 328.53122 10.031984)
					(mid 328.477338 10.054302)
					(end 328.45502 10.108184)
				)
				(arc
					(start 328.45502 11.205464)
					(mid 328.477338 11.259346)
					(end 328.53122 11.281664)
				)
				(arc
					(start 329.14336 11.281664)
					(mid 329.197242 11.259346)
					(end 329.21956 11.205464)
				)
			)
		)
	)
	(zone
		(layer "In16.Cu")
		(hatch none 0.5)
		(connect_pads
			(clearance 0)
		)
		(min_thickness 0.25)
		(keepout
			(tracks not_allowed)
			(vias allowed)
			(pads allowed)
			(copperpour not_allowed)
			(footprints allowed)
		)
		(placement
			(enabled no)
			(sheetname "")
		)
		(fill
			(thermal_gap 0.5)
			(thermal_bridge_width 0.5)
			(island_removal_mode 0)
		)
		(polygon
			(pts
				(arc
					(start 313.006232 11.198352)
					(mid 313.02855 11.252234)
					(end 313.082432 11.274552)
				)
				(arc
					(start 313.694572 11.274552)
					(mid 313.748454 11.252234)
					(end 313.770772 11.198352)
				)
				(arc
					(start 313.770772 10.101072)
					(mid 313.748454 10.04719)
					(end 313.694572 10.024872)
				)
				(arc
					(start 313.082432 10.024872)
					(mid 313.02855 10.04719)
					(end 313.006232 10.101072)
				)
			)
		)
	)
	(zone
		(layer "In16.Cu")
		(hatch none 0.5)
		(connect_pads
			(clearance 0)
		)
		(min_thickness 0.25)
		(keepout
			(tracks not_allowed)
			(vias allowed)
			(pads allowed)
			(copperpour not_allowed)
			(footprints allowed)
		)
		(placement
			(enabled no)
			(sheetname "")
		)
		(fill
			(thermal_gap 0.5)
			(thermal_bridge_width 0.5)
			(island_removal_mode 0)
		)
		(polygon
			(pts
				(arc
					(start 385.777232 11.231372)
					(mid 385.79955 11.285254)
					(end 385.853432 11.307572)
				)
				(arc
					(start 386.465572 11.307572)
					(mid 386.519454 11.285254)
					(end 386.541772 11.231372)
				)
				(arc
					(start 386.541772 10.134092)
					(mid 386.519454 10.08021)
					(end 386.465572 10.057892)
				)
				(arc
					(start 385.853432 10.057892)
					(mid 385.79955 10.08021)
					(end 385.777232 10.134092)
				)
			)
		)
	)
	(zone
		(layer "In16.Cu")
		(hatch none 0.5)
		(connect_pads
			(clearance 0)
		)
		(min_thickness 0.25)
		(keepout
			(tracks not_allowed)
			(vias allowed)
			(pads allowed)
			(copperpour not_allowed)
			(footprints allowed)
		)
		(placement
			(enabled no)
			(sheetname "")
		)
		(fill
			(thermal_gap 0.5)
			(thermal_bridge_width 0.5)
			(island_removal_mode 0)
		)
		(polygon
			(pts
				(arc
					(start 256.44856 10.075164)
					(mid 256.426242 10.021282)
					(end 256.37236 9.998964)
				)
				(arc
					(start 255.76022 9.998964)
					(mid 255.706338 10.021282)
					(end 255.68402 10.075164)
				)
				(arc
					(start 255.68402 11.172444)
					(mid 255.706338 11.226326)
					(end 255.76022 11.248644)
				)
				(arc
					(start 256.37236 11.248644)
					(mid 256.426242 11.226326)
					(end 256.44856 11.172444)
				)
			)
		)
	)
	(zone
		(layer "In16.Cu")
		(hatch none 0.5)
		(connect_pads
			(clearance 0)
		)
		(min_thickness 0.25)
		(keepout
			(tracks not_allowed)
			(vias allowed)
			(pads allowed)
			(copperpour not_allowed)
			(footprints allowed)
		)
		(placement
			(enabled no)
			(sheetname "")
		)
		(fill
			(thermal_gap 0.5)
			(thermal_bridge_width 0.5)
			(island_removal_mode 0)
		)
		(polygon
			(pts
				(arc
					(start 376.796808 21.117052)
					(mid 376.819126 21.170934)
					(end 376.873008 21.193252)
				)
				(arc
					(start 377.485148 21.193252)
					(mid 377.53903 21.170934)
					(end 377.561348 21.117052)
				)
				(arc
					(start 377.561348 20.019772)
					(mid 377.53903 19.96589)
					(end 377.485148 19.943572)
				)
				(arc
					(start 376.873008 19.943572)
					(mid 376.819126 19.96589)
					(end 376.796808 20.019772)
				)
			)
		)
	)
	(zone
		(layer "In16.Cu")
		(hatch none 0.5)
		(connect_pads
			(clearance 0)
		)
		(min_thickness 0.25)
		(keepout
			(tracks not_allowed)
			(vias allowed)
			(pads allowed)
			(copperpour not_allowed)
			(footprints allowed)
		)
		(placement
			(enabled no)
			(sheetname "")
		)
		(fill
			(thermal_gap 0.5)
			(thermal_bridge_width 0.5)
			(island_removal_mode 0)
		)
		(polygon
			(pts
				(arc
					(start 401.48256 10.141204)
					(mid 401.460242 10.087322)
					(end 401.40636 10.065004)
				)
				(arc
					(start 400.79422 10.065004)
					(mid 400.740338 10.087322)
					(end 400.71802 10.141204)
				)
				(arc
					(start 400.71802 11.238484)
					(mid 400.740338 11.292366)
					(end 400.79422 11.314684)
				)
				(arc
					(start 401.40636 11.314684)
					(mid 401.460242 11.292366)
					(end 401.48256 11.238484)
				)
			)
		)
	)
	(zone
		(layer "In16.Cu")
		(hatch none 0.5)
		(connect_pads
			(clearance 0)
		)
		(min_thickness 0.25)
		(keepout
			(tracks not_allowed)
			(vias allowed)
			(pads allowed)
			(copperpour not_allowed)
			(footprints allowed)
		)
		(placement
			(enabled no)
			(sheetname "")
		)
		(fill
			(thermal_gap 0.5)
			(thermal_bridge_width 0.5)
			(island_removal_mode 0)
		)
		(polygon
			(pts
				(arc
					(start 339.37956 20.026884)
					(mid 339.357242 19.973002)
					(end 339.30336 19.950684)
				)
				(arc
					(start 338.69122 19.950684)
					(mid 338.637338 19.973002)
					(end 338.61502 20.026884)
				)
				(arc
					(start 338.61502 21.124164)
					(mid 338.637338 21.178046)
					(end 338.69122 21.200364)
				)
				(arc
					(start 339.30336 21.200364)
					(mid 339.357242 21.178046)
					(end 339.37956 21.124164)
				)
			)
		)
	)
	(zone
		(layer "In16.Cu")
		(hatch none 0.5)
		(connect_pads
			(clearance 0)
		)
		(min_thickness 0.25)
		(keepout
			(tracks not_allowed)
			(vias allowed)
			(pads allowed)
			(copperpour not_allowed)
			(footprints allowed)
		)
		(placement
			(enabled no)
			(sheetname "")
		)
		(fill
			(thermal_gap 0.5)
			(thermal_bridge_width 0.5)
			(island_removal_mode 0)
		)
		(polygon
			(pts
				(arc
					(start 404.02256 20.026884)
					(mid 404.000242 19.973002)
					(end 403.94636 19.950684)
				)
				(arc
					(start 403.33422 19.950684)
					(mid 403.280338 19.973002)
					(end 403.25802 20.026884)
				)
				(arc
					(start 403.25802 21.124164)
					(mid 403.280338 21.178046)
					(end 403.33422 21.200364)
				)
				(arc
					(start 403.94636 21.200364)
					(mid 404.000242 21.178046)
					(end 404.02256 21.124164)
				)
			)
		)
	)
)
